# S9S_MB_2U (Grand Teton) — schematic netlist excerpt (pin names and nets, part order shuffled) for the footprints in the layout excerpt that follows; sources: Cadence DE-HDL packaged netlist, KiCad conversion of 03242023_DA0F0TMBIJ0_F0T_Motherboard_J_brd_V01_OCP.brd

PC398_P1_2  Q_CAP  3300PF 50V 10% X7R  pkg 0402  page 289 : A = SW_P12V_PVCCFA_EHV_FIVRA_CPU1_L ; B = GND
C996  Q_CAP  10UF 6.3V 20% X6S  pkg C0402  page 74 : A = PVCCIN_CPU0 ; B = GND
H19  HOLE  EMPTY  pkg TH  page 311 : \1\ = NC

(kicad_pcb
	(version 20260206)
	(generator "pcbnew")
	(generator_version "10.0")
	(general
		(thickness 1.6)
		(legacy_teardrops no)
	)
	(paper "A4")
	(title_block
		(title "03242023_DA0F0TMBIJ0_F0T_Motherboard_J_brd_V01_OCP.brd")
		(comment 1 "Grand Teton / footprints 2179-2181 of 6105")
	)
	(layers
		(0 "F.Cu" signal "TOP")
		(4 "In1.Cu" signal "GND")
		(6 "In2.Cu" signal "IN1")
		(8 "In3.Cu" signal "GND1")
		(10 "In4.Cu" signal "IN2")
		(12 "In5.Cu" signal "GND2")
		(14 "In6.Cu" signal "IN3")
		(16 "In7.Cu" signal "GND3")
		(18 "In8.Cu" signal "VCC")
		(20 "In9.Cu" signal "VCC1")
		(22 "In10.Cu" signal "GND4")
		(24 "In11.Cu" signal "IN4")
		(26 "In12.Cu" signal "GND5")
		(28 "In13.Cu" signal "IN5")
		(30 "In14.Cu" signal "GND6")
		(32 "In15.Cu" signal "IN6")
		(34 "In16.Cu" signal "GND7")
		(2 "B.Cu" signal "BOTTOM")
		(9 "F.Adhes" user "F.Adhesive")
		(11 "B.Adhes" user "B.Adhesive")
		(13 "F.Paste" user "Package Geometry/Pastemask Top")
		(15 "B.Paste" user "Package Geometry/Pastemask Bottom")
		(5 "F.SilkS" user "Ref Des/Silkscreen Top")
		(7 "B.SilkS" user "Ref Des/Silkscreen Bottom")
		(1 "F.Mask" user "Board Geometry/Soldermask Top")
		(3 "B.Mask" user "Board Geometry/Soldermask Bottom")
		(17 "Dwgs.User" user "User.Drawings")
		(19 "Cmts.User" user "User.Comments")
		(21 "Eco1.User" user "User.Eco1")
		(23 "Eco2.User" user "User.Eco2")
		(25 "Edge.Cuts" user "Board Geometry/Outline")
		(27 "Margin" user)
		(31 "F.CrtYd" user "Package Geometry/Place Bound Top")
		(29 "B.CrtYd" user "Package Geometry/Place Bound Bottom")
		(35 "F.Fab" user "Ref Des/Assembly Top")
		(33 "B.Fab" user "Ref Des/Assembly Bottom")
	)
	(footprint ""
		(layer "F.Cu")
		(at 367.44783 -256.654046 -90)
		(property "Reference" "C996"
			(at 0 0 270)
			(layer "F.SilkS")
			(hide yes)
			(effects
				(font
					(size 1.27 1.27)
				)
			)
		)
		(property "Value" ""
			(at 0 0 270)
			(layer "F.Fab")
			(effects
				(font
					(size 1.27 1.27)
				)
			)
		)
		(duplicate_pad_numbers_are_jumpers no)
		(fp_line
			(start -0.7874 0.4064)
			(end -0.7874 -0.4064)
			(stroke
				(width 0.1524)
				(type default)
			)
			(layer "F.SilkS")
		)
		(fp_line
			(start 0.7874 0.4064)
			(end -0.7874 0.4064)
			(stroke
				(width 0.1524)
				(type default)
			)
			(layer "F.SilkS")
		)
		(fp_line
			(start -0.7874 -0.4064)
			(end 0.7874 -0.4064)
			(stroke
				(width 0.1524)
				(type default)
			)
			(layer "F.SilkS")
		)
		(fp_line
			(start 0.7874 -0.4064)
			(end 0.7874 0.4064)
			(stroke
				(width 0.1524)
				(type default)
			)
			(layer "F.SilkS")
		)
		(fp_line
			(start -0.67945 0.3048)
			(end -0.67945 -0.305054)
			(stroke
				(width 0.1)
				(type default)
			)
			(layer "F.Fab")
		)
		(fp_line
			(start -0.12065 0.3048)
			(end -0.67945 0.3048)
			(stroke
				(width 0.1)
				(type default)
			)
			(layer "F.Fab")
		)
		(fp_line
			(start 0.120396 0.3048)
			(end 0.120396 0.2794)
			(stroke
				(width 0.1)
				(type default)
			)
			(layer "F.Fab")
		)
		(fp_line
			(start 0.67945 0.3048)
			(end 0.120396 0.3048)
			(stroke
				(width 0.1)
				(type default)
			)
			(layer "F.Fab")
		)
		(fp_line
			(start -0.12065 0.2794)
			(end -0.12065 0.3048)
			(stroke
				(width 0.1)
				(type default)
			)
			(layer "F.Fab")
		)
		(fp_line
			(start 0.120396 0.2794)
			(end -0.12065 0.2794)
			(stroke
				(width 0.1)
				(type default)
			)
			(layer "F.Fab")
		)
		(fp_line
			(start -0.12065 -0.2794)
			(end 0.12065 -0.2794)
			(stroke
				(width 0.1)
				(type default)
			)
			(layer "F.Fab")
		)
		(fp_line
			(start 0.12065 -0.2794)
			(end 0.12065 -0.3048)
			(stroke
				(width 0.1)
				(type default)
			)
			(layer "F.Fab")
		)
		(fp_line
			(start 0.12065 -0.3048)
			(end 0.67945 -0.3048)
			(stroke
				(width 0.1)
				(type default)
			)
			(layer "F.Fab")
		)
		(fp_line
			(start 0.67945 -0.3048)
			(end 0.67945 0.3048)
			(stroke
				(width 0.1)
				(type default)
			)
			(layer "F.Fab")
		)
		(fp_line
			(start -0.67945 -0.305054)
			(end -0.12065 -0.305054)
			(stroke
				(width 0.1)
				(type default)
			)
			(layer "F.Fab")
		)
		(fp_line
			(start -0.12065 -0.305054)
			(end -0.12065 -0.2794)
			(stroke
				(width 0.1)
				(type default)
			)
			(layer "F.Fab")
		)
		(pad "1" smd circle
			(at -0.40005 0 270)
			(size 0 0)
			(layers "F.Cu" "F.Mask" "F.Paste")
			(net "PVCCIN_CPU0")
		)
		(pad "2" smd circle
			(at 0.40005 0 270)
			(size 0 0)
			(layers "F.Cu" "F.Mask" "F.Paste")
			(net "GND")
		)
	)
	(footprint ""
		(layer "F.Cu")
		(at 393.880086 -251.76988)
		(property "Reference" "H19"
			(at 4.645914 -4.708398 0)
			(unlocked yes)
			(layer "F.SilkS")
			(effects
				(font
					(size 0.7874 0.5842)
					(thickness 0.1524)
				)
				(justify left)
			)
		)
		(property "Value" ""
			(at 0 0 0)
			(layer "F.Fab")
			(effects
				(font
					(size 1.27 1.27)
				)
			)
		)
		(duplicate_pad_numbers_are_jumpers no)
		(fp_circle
			(center 0 0)
			(end 2.5273 0)
			(stroke
				(width 0.1524)
				(type default)
			)
			(fill no)
			(layer "F.SilkS")
		)
		(fp_circle
			(center 0 0)
			(end 2.5273 0)
			(stroke
				(width 0.1524)
				(type default)
			)
			(fill no)
			(layer "B.SilkS")
		)
		(fp_circle
			(center 0 0)
			(end 2.5273 0)
			(stroke
				(width 0.1)
				(type default)
			)
			(fill no)
			(layer "B.Fab")
		)
		(fp_circle
			(center 0 0)
			(end 2.5273 0)
			(stroke
				(width 0.1)
				(type default)
			)
			(fill no)
			(layer "F.Fab")
		)
		(pad "" np_thru_hole circle
			(at 0 0)
			(size 3.429 3.429)
			(drill 3.429)
			(layers "*.Cu" "*.Mask")
			(clearance 0.381)
			(thermal_gap 0.381)
		)
	)
	(footprint ""
		(layer "F.Cu")
		(at 55.978298 -353.643946 -90)
		(property "Reference" "PC398_P1_2"
			(at 0 0 270)
			(layer "F.SilkS")
			(hide yes)
			(effects
				(font
					(size 1.27 1.27)
				)
			)
		)
		(property "Value" ""
			(at 0 0 270)
			(layer "F.Fab")
			(effects
				(font
					(size 1.27 1.27)
				)
			)
		)
		(duplicate_pad_numbers_are_jumpers no)
		(fp_line
			(start -0.7874 0.4064)
			(end -0.7874 -0.4064)
			(stroke
				(width 0.1524)
				(type default)
			)
			(layer "F.SilkS")
		)
		(fp_line
			(start 0.7874 0.4064)
			(end -0.7874 0.4064)
			(stroke
				(width 0.1524)
				(type default)
			)
			(layer "F.SilkS")
		)
		(fp_line
			(start -0.7874 -0.4064)
			(end 0.7874 -0.4064)
			(stroke
				(width 0.1524)
				(type default)
			)
			(layer "F.SilkS")
		)
		(fp_line
			(start 0.7874 -0.4064)
			(end 0.7874 0.4064)
			(stroke
				(width 0.1524)
				(type default)
			)
			(layer "F.SilkS")
		)
		(fp_line
			(start -0.67945 0.3048)
			(end -0.67945 -0.305054)
			(stroke
				(width 0.1)
				(type default)
			)
			(layer "F.Fab")
		)
		(fp_line
			(start -0.12065 0.3048)
			(end -0.67945 0.3048)
			(stroke
				(width 0.1)
				(type default)
			)
			(layer "F.Fab")
		)
		(fp_line
			(start 0.120396 0.3048)
			(end 0.120396 0.2794)
			(stroke
				(width 0.1)
				(type default)
			)
			(layer "F.Fab")
		)
		(fp_line
			(start 0.67945 0.3048)
			(end 0.120396 0.3048)
			(stroke
				(width 0.1)
				(type default)
			)
			(layer "F.Fab")
		)
		(fp_line
			(start -0.12065 0.2794)
			(end -0.12065 0.3048)
			(stroke
				(width 0.1)
				(type default)
			)
			(layer "F.Fab")
		)
		(fp_line
			(start 0.120396 0.2794)
			(end -0.12065 0.2794)
			(stroke
				(width 0.1)
				(type default)
			)
			(layer "F.Fab")
		)
		(fp_line
			(start -0.12065 -0.2794)
			(end 0.12065 -0.2794)
			(stroke
				(width 0.1)
				(type default)
			)
			(layer "F.Fab")
		)
		(fp_line
			(start 0.12065 -0.2794)
			(end 0.12065 -0.3048)
			(stroke
				(width 0.1)
				(type default)
			)
			(layer "F.Fab")
		)
		(fp_line
			(start 0.12065 -0.3048)
			(end 0.67945 -0.3048)
			(stroke
				(width 0.1)
				(type default)
			)
			(layer "F.Fab")
		)
		(fp_line
			(start 0.67945 -0.3048)
			(end 0.67945 0.3048)
			(stroke
				(width 0.1)
				(type default)
			)
			(layer "F.Fab")
		)
		(fp_line
			(start -0.67945 -0.305054)
			(end -0.12065 -0.305054)
			(stroke
				(width 0.1)
				(type default)
			)
			(layer "F.Fab")
		)
		(fp_line
			(start -0.12065 -0.305054)
			(end -0.12065 -0.2794)
			(stroke
				(width 0.1)
				(type default)
			)
			(layer "F.Fab")
		)
		(pad "1" smd circle
			(at -0.40005 0 270)
			(size 0 0)
			(layers "F.Cu" "F.Mask" "F.Paste")
			(net "SW_P12V_PVCCFA_EHV_FIVRA_CPU1_L")
		)
		(pad "2" smd circle
			(at 0.40005 0 270)
			(size 0 0)
			(layers "F.Cu" "F.Mask" "F.Paste")
			(net "GND")
		)
	)
)
